(kicad_pcb
	(version 20241229)
	(generator "pcbnew")
	(generator_version "9.0")
	(general
		(thickness 1.294)
		(legacy_teardrops no)
	)
	(paper "A3")
	(title_block
		(title "Kintex 410T devboard")
		(date "2024-04-03")
		(rev "1.1.2")
		(comment 9 "footprints 355-359 of 975")
	)
	(layers
		(0 "F.Cu" mixed)
		(4 "In1.Cu" power)
		(6 "In2.Cu" power)
		(8 "In3.Cu" mixed)
		(10 "In4.Cu" power)
		(12 "In5.Cu" mixed)
		(14 "In6.Cu" power)
		(16 "In7.Cu" mixed)
		(18 "In8.Cu" power)
		(2 "B.Cu" mixed)
		(9 "F.Adhes" user "F.Adhesive")
		(11 "B.Adhes" user "B.Adhesive")
		(13 "F.Paste" user)
		(15 "B.Paste" user)
		(5 "F.SilkS" user "F.Silkscreen")
		(7 "B.SilkS" user "B.Silkscreen")
		(1 "F.Mask" user)
		(3 "B.Mask" user)
		(17 "Dwgs.User" user "User.Drawings")
		(19 "Cmts.User" user "User.Comments")
		(21 "Eco1.User" user "User.Eco1")
		(23 "Eco2.User" user "User.Eco2")
		(25 "Edge.Cuts" user)
		(27 "Margin" user)
		(31 "F.CrtYd" user "F.Courtyard")
		(29 "B.CrtYd" user "B.Courtyard")
		(35 "F.Fab" user)
		(33 "B.Fab" user)
	)
	(footprint "antmicro-footprints:C_0402_1005Metric"
		(layer "F.Cu")
		(at 230.4 141.6 180)
		(descr "Capacitor SMD 0402")
		(tags "capacitor SMD 0402")
		(property "Reference" "C365"
			(at -3.6 -0.35 0)
			(layer "F.SilkS")
			(effects
				(font
					(size 0.7 0.7)
					(thickness 0.15)
				)
				(justify right bottom)
			)
		)
		(property "Value" "C_22p_0402"
			(at 0 1.4 0)
			(layer "F.Fab")
			(effects
				(font
					(size 0.7 0.7)
					(thickness 0.15)
				)
				(justify right bottom)
			)
		)
		(property "Description" "SMD Multilayer Ceramic Capacitor, 22 pF, 50 V, 0402 [1005 Metric], ± 5%, C0G / NP0, CC Series"
			(at 0 0 180)
			(layer "F.Fab")
			(hide yes)
			(effects
				(font
					(size 1.27 1.27)
					(thickness 0.15)
				)
			)
		)
		(property "Author" "Antmicro"
			(at 460.8 283.2 0)
			(layer "F.Fab")
			(hide yes)
			(effects
				(font
					(size 1 1)
					(thickness 0.15)
				)
			)
		)
		(property "Dielectric" ""
			(at 460.8 283.2 0)
			(layer "F.Fab")
			(hide yes)
			(effects
				(font
					(size 1 1)
					(thickness 0.15)
				)
			)
		)
		(property "License" "Apache-2.0"
			(at 460.8 283.2 0)
			(layer "F.Fab")
			(hide yes)
			(effects
				(font
					(size 1 1)
					(thickness 0.15)
				)
			)
		)
		(property "MPN" "CC0402JRNPO9BN220"
			(at 460.8 283.2 0)
			(layer "F.Fab")
			(hide yes)
			(effects
				(font
					(size 1 1)
					(thickness 0.15)
				)
			)
		)
		(property "Manufacturer" "YAGEO"
			(at 460.8 283.2 0)
			(layer "F.Fab")
			(hide yes)
			(effects
				(font
					(size 1 1)
					(thickness 0.15)
				)
			)
		)
		(property "Val" "22p"
			(at 460.8 283.2 0)
			(layer "F.Fab")
			(hide yes)
			(effects
				(font
					(size 1 1)
					(thickness 0.15)
				)
			)
		)
		(property "Voltage" ""
			(at 460.8 283.2 0)
			(layer "F.Fab")
			(hide yes)
			(effects
				(font
					(size 1 1)
					(thickness 0.15)
				)
			)
		)
		(sheetname "Clocks")
		(sheetfile "clocks.kicad_sch")
		(attr smd)
		(fp_rect
			(start -0.925 -0.47)
			(end 0.925 0.47)
			(stroke
				(width 0.05)
				(type default)
			)
			(fill no)
			(layer "F.CrtYd")
		)
		(fp_line
			(start 0.504 0.248)
			(end -0.494 0.248)
			(stroke
				(width 0.15)
				(type solid)
			)
			(layer "F.Fab")
		)
		(fp_line
			(start 0.504 -0.25)
			(end 0.504 0.248)
			(stroke
				(width 0.15)
				(type solid)
			)
			(layer "F.Fab")
		)
		(fp_line
			(start -0.494 0.248)
			(end -0.494 -0.25)
			(stroke
				(width 0.15)
				(type solid)
			)
			(layer "F.Fab")
		)
		(fp_line
			(start -0.494 -0.25)
			(end 0.504 -0.25)
			(stroke
				(width 0.15)
				(type solid)
			)
			(layer "F.Fab")
		)
		(pad "1" smd roundrect
			(at -0.48 0 180)
			(size 0.59 0.64)
			(layers "F.Cu" "F.Mask" "F.Paste")
			(roundrect_rratio 0.25)
			(net 1 "GND")
			(pintype "passive")
		)
		(pad "2" smd roundrect
			(at 0.48 0 180)
			(size 0.59 0.64)
			(layers "F.Cu" "F.Mask" "F.Paste")
			(roundrect_rratio 0.25)
			(net 752 "/Clocks/PLL_XI")
			(pintype "passive")
		)
	)
	(footprint "antmicro-footprints:C_0402_1005Metric"
		(layer "F.Cu")
		(at 173.570001 127.462501 180)
		(descr "Capacitor SMD 0402")
		(tags "capacitor SMD 0402")
		(property "Reference" "C311"
			(at -3.729999 -0.389999 0)
			(layer "F.SilkS")
			(effects
				(font
					(size 0.7 0.7)
					(thickness 0.15)
				)
				(justify right bottom)
			)
		)
		(property "Value" "C_100n_0402"
			(at 0 1.4 0)
			(layer "F.Fab")
			(effects
				(font
					(size 0.7 0.7)
					(thickness 0.15)
				)
				(justify right bottom)
			)
		)
		(property "Description" "SMD Multilayer Ceramic Capacitor, 0.1 µF, 50 V, 0402 [1005 Metric], ± 10%, X5R, GRM Series"
			(at 0 0 180)
			(layer "F.Fab")
			(hide yes)
			(effects
				(font
					(size 1.27 1.27)
					(thickness 0.15)
				)
			)
		)
		(property "Author" "Antmicro"
			(at 347.140002 254.925002 0)
			(layer "F.Fab")
			(hide yes)
			(effects
				(font
					(size 1 1)
					(thickness 0.15)
				)
			)
		)
		(property "Dielectric" "X5R"
			(at 347.140002 254.925002 0)
			(layer "F.Fab")
			(hide yes)
			(effects
				(font
					(size 1 1)
					(thickness 0.15)
				)
			)
		)
		(property "License" "Apache-2.0"
			(at 347.140002 254.925002 0)
			(layer "F.Fab")
			(hide yes)
			(effects
				(font
					(size 1 1)
					(thickness 0.15)
				)
			)
		)
		(property "MPN" "GRM155R61H104KE14D"
			(at 347.140002 254.925002 0)
			(layer "F.Fab")
			(hide yes)
			(effects
				(font
					(size 1 1)
					(thickness 0.15)
				)
			)
		)
		(property "Manufacturer" "Murata"
			(at 347.140002 254.925002 0)
			(layer "F.Fab")
			(hide yes)
			(effects
				(font
					(size 1 1)
					(thickness 0.15)
				)
			)
		)
		(property "Val" "100n"
			(at 347.140002 254.925002 0)
			(layer "F.Fab")
			(hide yes)
			(effects
				(font
					(size 1 1)
					(thickness 0.15)
				)
			)
		)
		(property "Voltage" "50V"
			(at 347.140002 254.925002 0)
			(layer "F.Fab")
			(hide yes)
			(effects
				(font
					(size 1 1)
					(thickness 0.15)
				)
			)
		)
		(sheetname "FMC+ HSPC")
		(sheetfile "fmc-hspc.kicad_sch")
		(attr smd)
		(fp_rect
			(start -0.925 -0.47)
			(end 0.925 0.47)
			(stroke
				(width 0.05)
				(type default)
			)
			(fill no)
			(layer "F.CrtYd")
		)
		(fp_line
			(start 0.504 0.248)
			(end -0.494 0.248)
			(stroke
				(width 0.15)
				(type solid)
			)
			(layer "F.Fab")
		)
		(fp_line
			(start 0.504 -0.25)
			(end 0.504 0.248)
			(stroke
				(width 0.15)
				(type solid)
			)
			(layer "F.Fab")
		)
		(fp_line
			(start -0.494 0.248)
			(end -0.494 -0.25)
			(stroke
				(width 0.15)
				(type solid)
			)
			(layer "F.Fab")
		)
		(fp_line
			(start -0.494 -0.25)
			(end 0.504 -0.25)
			(stroke
				(width 0.15)
				(type solid)
			)
			(layer "F.Fab")
		)
		(pad "1" smd roundrect
			(at -0.48 0 180)
			(size 0.59 0.64)
			(layers "F.Cu" "F.Mask" "F.Paste")
			(roundrect_rratio 0.25)
			(net 115 "/FMC+ HSPC/GTX115.TX1_N")
			(pintype "passive")
		)
		(pad "2" smd roundrect
			(at 0.48 0 180)
			(size 0.59 0.64)
			(layers "F.Cu" "F.Mask" "F.Paste")
			(roundrect_rratio 0.25)
			(net 109 "/FMC+ HSPC/GTX_TX6_C_N")
			(pintype "passive")
		)
	)
	(footprint "antmicro-footprints:R_0402_1005Metric"
		(layer "F.Cu")
		(at 193.6 165.649 90)
		(descr "Resistor SMD 0402")
		(tags "resistor SMD 0402")
		(property "Reference" "R331"
			(at -4.851 2.075 90)
			(layer "F.SilkS")
			(effects
				(font
					(size 0.7 0.7)
					(thickness 0.15)
				)
				(justify left bottom)
			)
		)
		(property "Value" "R_80k6_0402"
			(at 0 1.4 90)
			(layer "F.Fab")
			(effects
				(font
					(size 0.7 0.7)
					(thickness 0.15)
				)
				(justify left bottom)
			)
		)
		(property "Description" "SMD Chip Resistor, 80.6 kohm, ± 1%, 100 mW, 0402 [1005 Metric], Thick Film, Precision"
			(at 0 0 90)
			(layer "F.Fab")
			(hide yes)
			(effects
				(font
					(size 1.27 1.27)
					(thickness 0.15)
				)
			)
		)
		(property "Author" "Antmicro"
			(at 359.249 -27.951 0)
			(layer "F.Fab")
			(hide yes)
			(effects
				(font
					(size 1 1)
					(thickness 0.15)
				)
			)
		)
		(property "License" "Apache-2.0"
			(at 359.249 -27.951 0)
			(layer "F.Fab")
			(hide yes)
			(effects
				(font
					(size 1 1)
					(thickness 0.15)
				)
			)
		)
		(property "MPN" "CR0402-FX-8062GLF"
			(at 359.249 -27.951 0)
			(layer "F.Fab")
			(hide yes)
			(effects
				(font
					(size 1 1)
					(thickness 0.15)
				)
			)
		)
		(property "Manufacturer" "Bourns"
			(at 359.249 -27.951 0)
			(layer "F.Fab")
			(hide yes)
			(effects
				(font
					(size 1 1)
					(thickness 0.15)
				)
			)
		)
		(property "Tolerance" "1%"
			(at 359.249 -27.951 0)
			(layer "F.Fab")
			(hide yes)
			(effects
				(font
					(size 1 1)
					(thickness 0.15)
				)
			)
		)
		(property "Val" "80k6"
			(at 359.249 -27.951 0)
			(layer "F.Fab")
			(hide yes)
			(effects
				(font
					(size 1 1)
					(thickness 0.15)
				)
			)
		)
		(sheetname "DC-DC Converters")
		(sheetfile "dc-dc.kicad_sch")
		(attr smd)
		(fp_rect
			(start -0.925 -0.47)
			(end 0.925 0.47)
			(stroke
				(width 0.05)
				(type default)
			)
			(fill no)
			(layer "F.CrtYd")
		)
		(fp_rect
			(start -0.5 -0.25)
			(end 0.5 0.25)
			(stroke
				(width 0.15)
				(type solid)
			)
			(fill no)
			(layer "F.Fab")
		)
		(pad "1" smd roundrect
			(at -0.48 0 90)
			(size 0.59 0.64)
			(layers "F.Cu" "F.Mask" "F.Paste")
			(roundrect_rratio 0.25)
			(net 1230 "Net-(C364-Pad1)")
			(pintype "passive")
		)
		(pad "2" smd roundrect
			(at 0.48 0 90)
			(size 0.59 0.64)
			(layers "F.Cu" "F.Mask" "F.Paste")
			(roundrect_rratio 0.25)
			(net 751 "/DC-DC Converters/1V0_REG")
			(pintype "passive")
		)
	)
	(footprint "antmicro-footprints:C_0402_1005Metric"
		(layer "F.Cu")
		(at 199.901 106.199 180)
		(descr "Capacitor SMD 0402")
		(tags "capacitor SMD 0402")
		(property "Reference" "C231"
			(at -0.899 -0.301 180)
			(layer "F.SilkS")
			(effects
				(font
					(size 0.7 0.7)
					(thickness 0.15)
				)
				(justify left bottom)
			)
		)
		(property "Value" "C_100n_0402"
			(at 0 1.169 180)
			(layer "F.Fab")
			(effects
				(font
					(size 0.7 0.7)
					(thickness 0.15)
				)
				(justify left bottom)
			)
		)
		(property "Description" "SMD Multilayer Ceramic Capacitor, 0.1 µF, 50 V, 0402 [1005 Metric], ± 10%, X5R, GRM Series"
			(at 0 0 180)
			(layer "F.Fab")
			(hide yes)
			(effects
				(font
					(size 1.27 1.27)
					(thickness 0.15)
				)
			)
		)
		(property "Author" "Antmicro"
			(at 399.802 212.398 0)
			(layer "F.Fab")
			(hide yes)
			(effects
				(font
					(size 1 1)
					(thickness 0.15)
				)
			)
		)
		(property "Dielectric" "X5R"
			(at 399.802 212.398 0)
			(layer "F.Fab")
			(hide yes)
			(effects
				(font
					(size 1 1)
					(thickness 0.15)
				)
			)
		)
		(property "License" "Apache-2.0"
			(at 399.802 212.398 0)
			(layer "F.Fab")
			(hide yes)
			(effects
				(font
					(size 1 1)
					(thickness 0.15)
				)
			)
		)
		(property "MPN" "GRM155R61H104KE14D"
			(at 399.802 212.398 0)
			(layer "F.Fab")
			(hide yes)
			(effects
				(font
					(size 1 1)
					(thickness 0.15)
				)
			)
		)
		(property "Manufacturer" "Murata"
			(at 399.802 212.398 0)
			(layer "F.Fab")
			(hide yes)
			(effects
				(font
					(size 1 1)
					(thickness 0.15)
				)
			)
		)
		(property "Val" "100n"
			(at 399.802 212.398 0)
			(layer "F.Fab")
			(hide yes)
			(effects
				(font
					(size 1 1)
					(thickness 0.15)
				)
			)
		)
		(property "Voltage" "50V"
			(at 399.802 212.398 0)
			(layer "F.Fab")
			(hide yes)
			(effects
				(font
					(size 1 1)
					(thickness 0.15)
				)
			)
		)
		(sheetname "USB PHY")
		(sheetfile "usb-phy.kicad_sch")
		(attr smd)
		(fp_rect
			(start -0.925 -0.47)
			(end 0.925 0.47)
			(stroke
				(width 0.05)
				(type default)
			)
			(fill no)
			(layer "F.CrtYd")
		)
		(fp_line
			(start 0.504 0.248)
			(end -0.494 0.248)
			(stroke
				(width 0.15)
				(type solid)
			)
			(layer "F.Fab")
		)
		(fp_line
			(start 0.504 -0.25)
			(end 0.504 0.248)
			(stroke
				(width 0.15)
				(type solid)
			)
			(layer "F.Fab")
		)
		(fp_line
			(start -0.494 0.248)
			(end -0.494 -0.25)
			(stroke
				(width 0.15)
				(type solid)
			)
			(layer "F.Fab")
		)
		(fp_line
			(start -0.494 -0.25)
			(end 0.504 -0.25)
			(stroke
				(width 0.15)
				(type solid)
			)
			(layer "F.Fab")
		)
		(pad "1" smd roundrect
			(at -0.48 0 180)
			(size 0.59 0.64)
			(layers "F.Cu" "F.Mask" "F.Paste")
			(roundrect_rratio 0.25)
			(net 1 "GND")
			(pintype "passive")
		)
		(pad "2" smd roundrect
			(at 0.48 0 180)
			(size 0.59 0.64)
			(layers "F.Cu" "F.Mask" "F.Paste")
			(roundrect_rratio 0.25)
			(net 24 "+3V3")
			(pintype "passive")
		)
	)
	(footprint "antmicro-footprints:R_0402_1005Metric"
		(layer "F.Cu")
		(at 218.4 150.8)
		(descr "Resistor SMD 0402")
		(tags "resistor SMD 0402")
		(property "Reference" "R231"
			(at -3.6 0.35 0)
			(layer "F.SilkS")
			(effects
				(font
					(size 0.7 0.7)
					(thickness 0.15)
				)
				(justify left bottom)
			)
		)
		(property "Value" "R_10R_0402"
			(at 0 1.4 0)
			(layer "F.Fab")
			(effects
				(font
					(size 0.7 0.7)
					(thickness 0.15)
				)
				(justify left bottom)
			)
		)
		(property "Description" "SMD Chip Resistor, 10 ohm, ± 1%, 62.5 mW, 0402 [1005 Metric], Thick Film, General Purpose"
			(at 0 0 0)
			(layer "F.Fab")
			(hide yes)
			(effects
				(font
					(size 1.27 1.27)
					(thickness 0.15)
				)
			)
		)
		(property "Author" "Antmicro"
			(at 0 0 0)
			(layer "F.Fab")
			(hide yes)
			(effects
				(font
					(size 1 1)
					(thickness 0.15)
				)
			)
		)
		(property "License" "Apache-2.0"
			(at 0 0 0)
			(layer "F.Fab")
			(hide yes)
			(effects
				(font
					(size 1 1)
					(thickness 0.15)
				)
			)
		)
		(property "MPN" "CR0402-FX-10R0GLF"
			(at 0 0 0)
			(layer "F.Fab")
			(hide yes)
			(effects
				(font
					(size 1 1)
					(thickness 0.15)
				)
			)
		)
		(property "Manufacturer" "Bourns"
			(at 0 0 0)
			(layer "F.Fab")
			(hide yes)
			(effects
				(font
					(size 1 1)
					(thickness 0.15)
				)
			)
		)
		(property "Tolerance" "1%"
			(at 0 0 0)
			(layer "F.Fab")
			(hide yes)
			(effects
				(font
					(size 1 1)
					(thickness 0.15)
				)
			)
		)
		(property "Val" "10R"
			(at 0 0 0)
			(layer "F.Fab")
			(hide yes)
			(effects
				(font
					(size 1 1)
					(thickness 0.15)
				)
			)
		)
		(sheetname "HDMI + Ethernet")
		(sheetfile "hdmi-ethernet.kicad_sch")
		(attr smd)
		(fp_rect
			(start -0.925 -0.47)
			(end 0.925 0.47)
			(stroke
				(width 0.05)
				(type default)
			)
			(fill no)
			(layer "F.CrtYd")
		)
		(fp_rect
			(start -0.5 -0.25)
			(end 0.5 0.25)
			(stroke
				(width 0.15)
				(type solid)
			)
			(fill no)
			(layer "F.Fab")
		)
		(pad "1" smd roundrect
			(at -0.48 0)
			(size 0.59 0.64)
			(layers "F.Cu" "F.Mask" "F.Paste")
			(roundrect_rratio 0.25)
			(net 511 "/FPGA Bank 18 & 32/ETH_RMII.TXEN")
			(pintype "passive")
		)
		(pad "2" smd roundrect
			(at 0.48 0)
			(size 0.59 0.64)
			(layers "F.Cu" "F.Mask" "F.Paste")
			(roundrect_rratio 0.25)
			(net 948 "/HDMI + Ethernet/ETH_PHY_TXEN")
			(pintype "passive")
		)
	)
)
